#ISCELL
  pure_quanta quanta_title_block_c *
  *
#ISCELL
  pure_quanta_power cad_note *
  *
#CELL
  pure_quanta genoa_sp5 *
  page18_i159
#ISCELL
  mstr_standard offpage *
  page18_i160
#ISCELL
  mstr_standard offpage *
  page18_i161
#ISCELL
  mstr_standard tap *
  page18_i162
#ISCELL
  mstr_standard tap *
  page18_i163
#ISCELL
  mstr_standard tap *
  page18_i164
#ISCELL
  mstr_standard tap *
  page18_i165
#ISCELL
  mstr_standard tap *
  page18_i166
#ISCELL
  mstr_standard tap *
  page18_i167
#ISCELL
  mstr_standard tap *
  page18_i168
#ISCELL
  mstr_standard tap *
  page18_i169
#ISCELL
  mstr_standard tap *
  page18_i170
#ISCELL
  mstr_standard tap *
  page18_i171
#ISCELL
  mstr_standard tap *
  page18_i172
#ISCELL
  mstr_standard tap *
  page18_i173
#ISCELL
  mstr_standard tap *
  page18_i174
#ISCELL
  mstr_standard tap *
  page18_i175
#ISCELL
  mstr_standard tap *
  page18_i176
#ISCELL
  mstr_standard tap *
  page18_i177
#ISCELL
  mstr_standard tap *
  page18_i178
#ISCELL
  mstr_standard tap *
  page18_i179
#ISCELL
  mstr_standard tap *
  page18_i180
#ISCELL
  mstr_standard tap *
  page18_i181
#ISCELL
  mstr_standard tap *
  page18_i182
#ISCELL
  mstr_standard tap *
  page18_i183
#ISCELL
  mstr_standard tap *
  page18_i184
#ISCELL
  mstr_standard tap *
  page18_i185
#ISCELL
  mstr_standard tap *
  page18_i186
#ISCELL
  mstr_standard tap *
  page18_i187
#ISCELL
  mstr_standard tap *
  page18_i188
#ISCELL
  mstr_standard tap *
  page18_i189
#ISCELL
  mstr_standard tap *
  page18_i190
#ISCELL
  mstr_standard tap *
  page18_i191
#ISCELL
  mstr_standard tap *
  page18_i192
#ISCELL
  mstr_standard tap *
  page18_i193
#ISCELL
  mstr_standard tap *
  page18_i194
#ISCELL
  mstr_standard tap *
  page18_i195
#ISCELL
  mstr_standard offpage *
  page18_i196
#ISCELL
  mstr_standard tap *
  page18_i197
#ISCELL
  mstr_standard tap *
  page18_i198
#ISCELL
  mstr_standard tap *
  page18_i199
#ISCELL
  mstr_standard tap *
  page18_i200
#ISCELL
  mstr_standard tap *
  page18_i201
#ISCELL
  mstr_standard tap *
  page18_i202
#ISCELL
  mstr_standard tap *
  page18_i203
#ISCELL
  mstr_standard tap *
  page18_i204
#ISCELL
  mstr_standard tap *
  page18_i205
#ISCELL
  mstr_standard tap *
  page18_i206
#ISCELL
  mstr_standard tap *
  page18_i207
#ISCELL
  mstr_standard tap *
  page18_i208
#ISCELL
  mstr_standard tap *
  page18_i209
#ISCELL
  mstr_standard tap *
  page18_i210
#ISCELL
  mstr_standard tap *
  page18_i211
#ISCELL
  mstr_standard tap *
  page18_i212
#ISCELL
  mstr_standard tap *
  page18_i213
#ISCELL
  mstr_standard tap *
  page18_i214
#ISCELL
  mstr_standard tap *
  page18_i215
#ISCELL
  mstr_standard tap *
  page18_i216
#ISCELL
  mstr_standard tap *
  page18_i217
#ISCELL
  mstr_standard tap *
  page18_i218
#ISCELL
  mstr_standard tap *
  page18_i219
#ISCELL
  mstr_standard tap *
  page18_i220
#ISCELL
  mstr_standard tap *
  page18_i221
#ISCELL
  mstr_standard tap *
  page18_i222
#ISCELL
  mstr_standard tap *
  page18_i223
#ISCELL
  mstr_standard tap *
  page18_i224
#ISCELL
  mstr_standard tap *
  page18_i225
#ISCELL
  mstr_standard tap *
  page18_i226
#ISCELL
  mstr_standard tap *
  page18_i227
#ISCELL
  mstr_standard tap *
  page18_i228
#ISCELL
  mstr_standard tap *
  page18_i229
#ISCELL
  mstr_standard tap *
  page18_i230
#ISCELL
  mstr_standard tap *
  page18_i231
#ISCELL
  mstr_standard tap *
  page18_i232
#ISCELL
  mstr_standard tap *
  page18_i233
#ISCELL
  mstr_standard offpage *
  page18_i234
#ISCELL
  mstr_standard tap *
  page18_i235
#ISCELL
  mstr_standard tap *
  page18_i236
#ISCELL
  mstr_standard tap *
  page18_i237
#ISCELL
  mstr_standard tap *
  page18_i238
#ISCELL
  mstr_standard tap *
  page18_i239
#ISCELL
  mstr_standard tap *
  page18_i240
#ISCELL
  mstr_standard tap *
  page18_i241
#ISCELL
  mstr_standard tap *
  page18_i242
#ISCELL
  mstr_standard tap *
  page18_i243
#ISCELL
  mstr_standard tap *
  page18_i244
#ISCELL
  mstr_standard tap *
  page18_i245
#ISCELL
  mstr_standard tap *
  page18_i246
#ISCELL
  mstr_standard tap *
  page18_i247
#ISCELL
  mstr_standard tap *
  page18_i248
#ISCELL
  mstr_standard tap *
  page18_i249
#ISCELL
  mstr_standard tap *
  page18_i250
#ISCELL
  mstr_standard tap *
  page18_i251
#ISCELL
  mstr_standard tap *
  page18_i252
#ISCELL
  mstr_standard tap *
  page18_i253
#ISCELL
  mstr_standard tap *
  page18_i254
#ISCELL
  mstr_standard tap *
  page18_i255
#ISCELL
  mstr_standard tap *
  page18_i256
#ISCELL
  mstr_standard tap *
  page18_i257
#ISCELL
  mstr_standard tap *
  page18_i258
#ISCELL
  mstr_standard tap *
  page18_i259
#ISCELL
  mstr_standard tap *
  page18_i260
#ISCELL
  mstr_standard tap *
  page18_i261
#ISCELL
  mstr_standard tap *
  page18_i262
#ISCELL
  mstr_standard tap *
  page18_i263
#ISCELL
  mstr_standard tap *
  page18_i264
#ISCELL
  mstr_standard tap *
  page18_i265
#ISCELL
  mstr_standard tap *
  page18_i266
#ISCELL
  mstr_standard tap *
  page18_i267
#ISCELL
  mstr_standard tap *
  page18_i268
#ISCELL
  mstr_standard tap *
  page18_i269
#ISCELL
  mstr_standard tap *
  page18_i270
#ISCELL
  mstr_standard tap *
  page18_i271
#ISCELL
  mstr_standard tap *
  page18_i272
#ISCELL
  mstr_standard tap *
  page18_i273
#ISCELL
  mstr_standard tap *
  page18_i274
#ISCELL
  mstr_standard tap *
  page18_i275
#ISCELL
  mstr_standard tap *
  page18_i276
#ISCELL
  mstr_standard tap *
  page18_i277
#ISCELL
  mstr_standard tap *
  page18_i278
#ISCELL
  mstr_standard tap *
  page18_i279
#ISCELL
  mstr_standard tap *
  page18_i280
#ISCELL
  standard offpage *
  page18_i281
#ISCELL
  standard offpage *
  page18_i282
#ISCELL
  standard offpage *
  page18_i283
#ISCELL
  standard offpage *
  page18_i284
#ISCELL
  mstr_standard tap *
  page18_i285
#ISCELL
  mstr_standard tap *
  page18_i286
#ISCELL
  mstr_standard tap *
  page18_i287
#ISCELL
  mstr_standard tap *
  page18_i288
#ISCELL
  mstr_standard tap *
  page18_i289
#ISCELL
  mstr_standard tap *
  page18_i290
#ISCELL
  mstr_standard tap *
  page18_i291
#ISCELL
  mstr_standard tap *
  page18_i292
#ISCELL
  mstr_standard tap *
  page18_i293
#ISCELL
  mstr_standard tap *
  page18_i294
#ISCELL
  mstr_standard tap *
  page18_i295
#ISCELL
  mstr_standard tap *
  page18_i296
#ISCELL
  mstr_standard tap *
  page18_i297
#ISCELL
  mstr_standard tap *
  page18_i298
#ISCELL
  mstr_standard tap *
  page18_i299
#ISCELL
  mstr_standard tap *
  page18_i300
#ISCELL
  mstr_standard tap *
  page18_i301
#ISCELL
  standard offpage *
  page18_i302
#ISCELL
  standard offpage *
  page18_i303
#ISCELL
  standard offpage *
  page18_i304
#ISCELL
  standard offpage *
  page18_i305
#ISCELL
  standard offpage *
  page18_i306
#ISCELL
  standard offpage *
  page18_i307
#ISCELL
  standard offpage *
  page18_i308
#ISCELL
  mstr_standard offpage *
  page18_i309
#ISCELL
  standard offpage *
  page18_i310
#ISCELL
  standard offpage *
  page18_i311
#ISCELL
  standard offpage *
  page18_i312
#ISCELL
  standard offpage *
  page18_i313
#CELL
  pure_quanta q_res *
  page18_i314
#ISCELL
  mstr_standard offpage *
  page18_i315
#ISCELL
  standard offpage *
  page18_i316
